(kicad_pcb
	(version 20260206)
	(generator "pcbnew")
	(generator_version "10.0")
	(general
		(thickness 1.6)
		(legacy_teardrops no)
	)
	(paper "A4")
	(title_block
		(title "03242023_DA0F0TMBIJ0_F0T_Motherboard_J_brd_V01_OCP.brd")
		(comment 1 "Grand Teton / footprints 1466-1472 of 6105")
	)
	(layers
		(0 "F.Cu" signal "TOP")
		(4 "In1.Cu" signal "GND")
		(6 "In2.Cu" signal "IN1")
		(8 "In3.Cu" signal "GND1")
		(10 "In4.Cu" signal "IN2")
		(12 "In5.Cu" signal "GND2")
		(14 "In6.Cu" signal "IN3")
		(16 "In7.Cu" signal "GND3")
		(18 "In8.Cu" signal "VCC")
		(20 "In9.Cu" signal "VCC1")
		(22 "In10.Cu" signal "GND4")
		(24 "In11.Cu" signal "IN4")
		(26 "In12.Cu" signal "GND5")
		(28 "In13.Cu" signal "IN5")
		(30 "In14.Cu" signal "GND6")
		(32 "In15.Cu" signal "IN6")
		(34 "In16.Cu" signal "GND7")
		(2 "B.Cu" signal "BOTTOM")
		(9 "F.Adhes" user "F.Adhesive")
		(11 "B.Adhes" user "B.Adhesive")
		(13 "F.Paste" user "Package Geometry/Pastemask Top")
		(15 "B.Paste" user "Package Geometry/Pastemask Bottom")
		(5 "F.SilkS" user "Ref Des/Silkscreen Top")
		(7 "B.SilkS" user "Ref Des/Silkscreen Bottom")
		(1 "F.Mask" user "Board Geometry/Soldermask Top")
		(3 "B.Mask" user "Board Geometry/Soldermask Bottom")
		(17 "Dwgs.User" user "User.Drawings")
		(19 "Cmts.User" user "User.Comments")
		(21 "Eco1.User" user "User.Eco1")
		(23 "Eco2.User" user "User.Eco2")
		(25 "Edge.Cuts" user "Board Geometry/Outline")
		(27 "Margin" user)
		(31 "F.CrtYd" user "Package Geometry/Place Bound Top")
		(29 "B.CrtYd" user "Package Geometry/Place Bound Bottom")
		(35 "F.Fab" user "Ref Des/Assembly Top")
		(33 "B.Fab" user "Ref Des/Assembly Bottom")
	)
	(footprint ""
		(layer "F.Cu")
		(at 174.04588 -126.964948 -90)
		(property "Reference" "R1444"
			(at 0 0 270)
			(layer "F.SilkS")
			(hide yes)
			(effects
				(font
					(size 1.27 1.27)
				)
			)
		)
		(property "Value" ""
			(at 0 0 270)
			(layer "F.Fab")
			(effects
				(font
					(size 1.27 1.27)
				)
			)
		)
		(duplicate_pad_numbers_are_jumpers no)
		(fp_line
			(start -0.7874 0.4064)
			(end -0.7874 -0.4064)
			(stroke
				(width 0.1524)
				(type default)
			)
			(layer "F.SilkS")
		)
		(fp_line
			(start 0.7874 0.4064)
			(end -0.7874 0.4064)
			(stroke
				(width 0.1524)
				(type default)
			)
			(layer "F.SilkS")
		)
		(fp_line
			(start -0.7874 -0.4064)
			(end 0.7874 -0.4064)
			(stroke
				(width 0.1524)
				(type default)
			)
			(layer "F.SilkS")
		)
		(fp_line
			(start 0.7874 -0.4064)
			(end 0.7874 0.4064)
			(stroke
				(width 0.1524)
				(type default)
			)
			(layer "F.SilkS")
		)
		(fp_line
			(start -0.67945 0.3048)
			(end -0.67945 -0.305054)
			(stroke
				(width 0.1)
				(type default)
			)
			(layer "F.Fab")
		)
		(fp_line
			(start -0.12065 0.3048)
			(end -0.67945 0.3048)
			(stroke
				(width 0.1)
				(type default)
			)
			(layer "F.Fab")
		)
		(fp_line
			(start 0.120396 0.3048)
			(end 0.120396 0.2794)
			(stroke
				(width 0.1)
				(type default)
			)
			(layer "F.Fab")
		)
		(fp_line
			(start 0.67945 0.3048)
			(end 0.120396 0.3048)
			(stroke
				(width 0.1)
				(type default)
			)
			(layer "F.Fab")
		)
		(fp_line
			(start -0.12065 0.2794)
			(end -0.12065 0.3048)
			(stroke
				(width 0.1)
				(type default)
			)
			(layer "F.Fab")
		)
		(fp_line
			(start 0.120396 0.2794)
			(end -0.12065 0.2794)
			(stroke
				(width 0.1)
				(type default)
			)
			(layer "F.Fab")
		)
		(fp_line
			(start -0.12065 -0.2794)
			(end 0.12065 -0.2794)
			(stroke
				(width 0.1)
				(type default)
			)
			(layer "F.Fab")
		)
		(fp_line
			(start 0.12065 -0.2794)
			(end 0.12065 -0.3048)
			(stroke
				(width 0.1)
				(type default)
			)
			(layer "F.Fab")
		)
		(fp_line
			(start 0.12065 -0.3048)
			(end 0.67945 -0.3048)
			(stroke
				(width 0.1)
				(type default)
			)
			(layer "F.Fab")
		)
		(fp_line
			(start 0.67945 -0.3048)
			(end 0.67945 0.3048)
			(stroke
				(width 0.1)
				(type default)
			)
			(layer "F.Fab")
		)
		(fp_line
			(start -0.67945 -0.305054)
			(end -0.12065 -0.305054)
			(stroke
				(width 0.1)
				(type default)
			)
			(layer "F.Fab")
		)
		(fp_line
			(start -0.12065 -0.305054)
			(end -0.12065 -0.2794)
			(stroke
				(width 0.1)
				(type default)
			)
			(layer "F.Fab")
		)
		(pad "1" smd circle
			(at -0.40005 0 270)
			(size 0 0)
			(layers "F.Cu" "F.Mask" "F.Paste")
			(net "PWRGD_P1V8_PCH_AUX")
		)
		(pad "2" smd circle
			(at 0.40005 0 270)
			(size 0 0)
			(layers "F.Cu" "F.Mask" "F.Paste")
			(net "PWRGD_P1V8_PCH_AUX_PLD")
		)
	)
	(footprint ""
		(layer "F.Cu")
		(at 366.48263 -258.726686 90)
		(property "Reference" "C976"
			(at 0 0 90)
			(layer "F.SilkS")
			(hide yes)
			(effects
				(font
					(size 1.27 1.27)
				)
			)
		)
		(property "Value" ""
			(at 0 0 90)
			(layer "F.Fab")
			(effects
				(font
					(size 1.27 1.27)
				)
			)
		)
		(duplicate_pad_numbers_are_jumpers no)
		(fp_line
			(start 0.7874 -0.4064)
			(end 0.7874 0.4064)
			(stroke
				(width 0.1524)
				(type default)
			)
			(layer "F.SilkS")
		)
		(fp_line
			(start -0.7874 -0.4064)
			(end 0.7874 -0.4064)
			(stroke
				(width 0.1524)
				(type default)
			)
			(layer "F.SilkS")
		)
		(fp_line
			(start 0.7874 0.4064)
			(end -0.7874 0.4064)
			(stroke
				(width 0.1524)
				(type default)
			)
			(layer "F.SilkS")
		)
		(fp_line
			(start -0.7874 0.4064)
			(end -0.7874 -0.4064)
			(stroke
				(width 0.1524)
				(type default)
			)
			(layer "F.SilkS")
		)
		(fp_line
			(start -0.12065 -0.305054)
			(end -0.12065 -0.2794)
			(stroke
				(width 0.1)
				(type default)
			)
			(layer "F.Fab")
		)
		(fp_line
			(start -0.67945 -0.305054)
			(end -0.12065 -0.305054)
			(stroke
				(width 0.1)
				(type default)
			)
			(layer "F.Fab")
		)
		(fp_line
			(start 0.67945 -0.3048)
			(end 0.67945 0.3048)
			(stroke
				(width 0.1)
				(type default)
			)
			(layer "F.Fab")
		)
		(fp_line
			(start 0.12065 -0.3048)
			(end 0.67945 -0.3048)
			(stroke
				(width 0.1)
				(type default)
			)
			(layer "F.Fab")
		)
		(fp_line
			(start 0.12065 -0.2794)
			(end 0.12065 -0.3048)
			(stroke
				(width 0.1)
				(type default)
			)
			(layer "F.Fab")
		)
		(fp_line
			(start -0.12065 -0.2794)
			(end 0.12065 -0.2794)
			(stroke
				(width 0.1)
				(type default)
			)
			(layer "F.Fab")
		)
		(fp_line
			(start 0.120396 0.2794)
			(end -0.12065 0.2794)
			(stroke
				(width 0.1)
				(type default)
			)
			(layer "F.Fab")
		)
		(fp_line
			(start -0.12065 0.2794)
			(end -0.12065 0.3048)
			(stroke
				(width 0.1)
				(type default)
			)
			(layer "F.Fab")
		)
		(fp_line
			(start 0.67945 0.3048)
			(end 0.120396 0.3048)
			(stroke
				(width 0.1)
				(type default)
			)
			(layer "F.Fab")
		)
		(fp_line
			(start 0.120396 0.3048)
			(end 0.120396 0.2794)
			(stroke
				(width 0.1)
				(type default)
			)
			(layer "F.Fab")
		)
		(fp_line
			(start -0.12065 0.3048)
			(end -0.67945 0.3048)
			(stroke
				(width 0.1)
				(type default)
			)
			(layer "F.Fab")
		)
		(fp_line
			(start -0.67945 0.3048)
			(end -0.67945 -0.305054)
			(stroke
				(width 0.1)
				(type default)
			)
			(layer "F.Fab")
		)
		(pad "1" smd circle
			(at -0.40005 0 90)
			(size 0 0)
			(layers "F.Cu" "F.Mask" "F.Paste")
			(net "PVCCIN_CPU0")
		)
		(pad "2" smd circle
			(at 0.40005 0 90)
			(size 0 0)
			(layers "F.Cu" "F.Mask" "F.Paste")
			(net "GND")
		)
	)
	(footprint ""
		(layer "F.Cu")
		(at 27.6352 -409.0416 -90)
		(property "Reference" "C1978"
			(at 0 0 270)
			(layer "F.SilkS")
			(hide yes)
			(effects
				(font
					(size 1.27 1.27)
				)
			)
		)
		(property "Value" ""
			(at 0 0 270)
			(layer "F.Fab")
			(effects
				(font
					(size 1.27 1.27)
				)
			)
		)
		(duplicate_pad_numbers_are_jumpers no)
		(fp_line
			(start -0.7874 0.4064)
			(end -0.7874 -0.4064)
			(stroke
				(width 0.1524)
				(type default)
			)
			(layer "F.SilkS")
		)
		(fp_line
			(start 0.7874 0.4064)
			(end -0.7874 0.4064)
			(stroke
				(width 0.1524)
				(type default)
			)
			(layer "F.SilkS")
		)
		(fp_line
			(start -0.7874 -0.4064)
			(end 0.7874 -0.4064)
			(stroke
				(width 0.1524)
				(type default)
			)
			(layer "F.SilkS")
		)
		(fp_line
			(start 0.7874 -0.4064)
			(end 0.7874 0.4064)
			(stroke
				(width 0.1524)
				(type default)
			)
			(layer "F.SilkS")
		)
		(fp_line
			(start -0.67945 0.3048)
			(end -0.67945 -0.305054)
			(stroke
				(width 0.1)
				(type default)
			)
			(layer "F.Fab")
		)
		(fp_line
			(start -0.12065 0.3048)
			(end -0.67945 0.3048)
			(stroke
				(width 0.1)
				(type default)
			)
			(layer "F.Fab")
		)
		(fp_line
			(start 0.120396 0.3048)
			(end 0.120396 0.2794)
			(stroke
				(width 0.1)
				(type default)
			)
			(layer "F.Fab")
		)
		(fp_line
			(start 0.67945 0.3048)
			(end 0.120396 0.3048)
			(stroke
				(width 0.1)
				(type default)
			)
			(layer "F.Fab")
		)
		(fp_line
			(start -0.12065 0.2794)
			(end -0.12065 0.3048)
			(stroke
				(width 0.1)
				(type default)
			)
			(layer "F.Fab")
		)
		(fp_line
			(start 0.120396 0.2794)
			(end -0.12065 0.2794)
			(stroke
				(width 0.1)
				(type default)
			)
			(layer "F.Fab")
		)
		(fp_line
			(start -0.12065 -0.2794)
			(end 0.12065 -0.2794)
			(stroke
				(width 0.1)
				(type default)
			)
			(layer "F.Fab")
		)
		(fp_line
			(start 0.12065 -0.2794)
			(end 0.12065 -0.3048)
			(stroke
				(width 0.1)
				(type default)
			)
			(layer "F.Fab")
		)
		(fp_line
			(start 0.12065 -0.3048)
			(end 0.67945 -0.3048)
			(stroke
				(width 0.1)
				(type default)
			)
			(layer "F.Fab")
		)
		(fp_line
			(start 0.67945 -0.3048)
			(end 0.67945 0.3048)
			(stroke
				(width 0.1)
				(type default)
			)
			(layer "F.Fab")
		)
		(fp_line
			(start -0.67945 -0.305054)
			(end -0.12065 -0.305054)
			(stroke
				(width 0.1)
				(type default)
			)
			(layer "F.Fab")
		)
		(fp_line
			(start -0.12065 -0.305054)
			(end -0.12065 -0.2794)
			(stroke
				(width 0.1)
				(type default)
			)
			(layer "F.Fab")
		)
		(pad "1" smd circle
			(at -0.40005 0 270)
			(size 0 0)
			(layers "F.Cu" "F.Mask" "F.Paste")
			(net "GPU_PRSNT_N_ISO")
		)
		(pad "2" smd circle
			(at 0.40005 0 270)
			(size 0 0)
			(layers "F.Cu" "F.Mask" "F.Paste")
			(net "GND")
		)
	)
	(footprint ""
		(layer "F.Cu")
		(at 443.7507 -51.059588 -90)
		(property "Reference" "C1333"
			(at 0 0 270)
			(layer "F.SilkS")
			(hide yes)
			(effects
				(font
					(size 1.27 1.27)
				)
			)
		)
		(property "Value" ""
			(at 0 0 270)
			(layer "F.Fab")
			(effects
				(font
					(size 1.27 1.27)
				)
			)
		)
		(duplicate_pad_numbers_are_jumpers no)
		(fp_line
			(start -1.524 0.762)
			(end -1.524 -0.762)
			(stroke
				(width 0.1524)
				(type default)
			)
			(layer "F.SilkS")
		)
		(fp_line
			(start 1.524 0.762)
			(end -1.524 0.762)
			(stroke
				(width 0.1524)
				(type default)
			)
			(layer "F.SilkS")
		)
		(fp_line
			(start -1.524 -0.762)
			(end 1.524 -0.762)
			(stroke
				(width 0.1524)
				(type default)
			)
			(layer "F.SilkS")
		)
		(fp_line
			(start 1.524 -0.762)
			(end 1.524 0.762)
			(stroke
				(width 0.1524)
				(type default)
			)
			(layer "F.SilkS")
		)
		(fp_line
			(start -1.1049 0.724916)
			(end 1.1049 0.724916)
			(stroke
				(width 0.1)
				(type default)
			)
			(layer "F.Fab")
		)
		(fp_line
			(start 1.1049 0.724916)
			(end 1.1049 -0.724916)
			(stroke
				(width 0.1)
				(type default)
			)
			(layer "F.Fab")
		)
		(fp_line
			(start -1.1049 -0.724916)
			(end -1.1049 0.724916)
			(stroke
				(width 0.1)
				(type default)
			)
			(layer "F.Fab")
		)
		(fp_line
			(start 1.1049 -0.724916)
			(end -1.1049 -0.724916)
			(stroke
				(width 0.1)
				(type default)
			)
			(layer "F.Fab")
		)
		(pad "1" smd rect
			(at -0.889 0 90)
			(size 1.016 1.27)
			(layers "F.Cu" "F.Mask" "F.Paste")
			(net "P3V3_AUX")
		)
		(pad "2" smd rect
			(at 0.889 0 90)
			(size 1.016 1.27)
			(layers "F.Cu" "F.Mask" "F.Paste")
			(net "GND")
		)
	)
	(footprint ""
		(layer "F.Cu")
		(at 259.021326 -131.502912)
		(property "Reference" "R4499"
			(at 0 0 0)
			(layer "F.SilkS")
			(hide yes)
			(effects
				(font
					(size 1.27 1.27)
				)
			)
		)
		(property "Value" ""
			(at 0 0 0)
			(layer "F.Fab")
			(effects
				(font
					(size 1.27 1.27)
				)
			)
		)
		(duplicate_pad_numbers_are_jumpers no)
		(fp_line
			(start -0.7874 -0.4064)
			(end 0.7874 -0.4064)
			(stroke
				(width 0.1524)
				(type default)
			)
			(layer "F.SilkS")
		)
		(fp_line
			(start -0.7874 0.4064)
			(end -0.7874 -0.4064)
			(stroke
				(width 0.1524)
				(type default)
			)
			(layer "F.SilkS")
		)
		(fp_line
			(start 0.7874 -0.4064)
			(end 0.7874 0.4064)
			(stroke
				(width 0.1524)
				(type default)
			)
			(layer "F.SilkS")
		)
		(fp_line
			(start 0.7874 0.4064)
			(end -0.7874 0.4064)
			(stroke
				(width 0.1524)
				(type default)
			)
			(layer "F.SilkS")
		)
		(fp_line
			(start -0.67945 -0.305054)
			(end -0.12065 -0.305054)
			(stroke
				(width 0.1)
				(type default)
			)
			(layer "F.Fab")
		)
		(fp_line
			(start -0.67945 0.3048)
			(end -0.67945 -0.305054)
			(stroke
				(width 0.1)
				(type default)
			)
			(layer "F.Fab")
		)
		(fp_line
			(start -0.12065 -0.305054)
			(end -0.12065 -0.2794)
			(stroke
				(width 0.1)
				(type default)
			)
			(layer "F.Fab")
		)
		(fp_line
			(start -0.12065 -0.2794)
			(end 0.12065 -0.2794)
			(stroke
				(width 0.1)
				(type default)
			)
			(layer "F.Fab")
		)
		(fp_line
			(start -0.12065 0.2794)
			(end -0.12065 0.3048)
			(stroke
				(width 0.1)
				(type default)
			)
			(layer "F.Fab")
		)
		(fp_line
			(start -0.12065 0.3048)
			(end -0.67945 0.3048)
			(stroke
				(width 0.1)
				(type default)
			)
			(layer "F.Fab")
		)
		(fp_line
			(start 0.120396 0.2794)
			(end -0.12065 0.2794)
			(stroke
				(width 0.1)
				(type default)
			)
			(layer "F.Fab")
		)
		(fp_line
			(start 0.120396 0.3048)
			(end 0.120396 0.2794)
			(stroke
				(width 0.1)
				(type default)
			)
			(layer "F.Fab")
		)
		(fp_line
			(start 0.12065 -0.3048)
			(end 0.67945 -0.3048)
			(stroke
				(width 0.1)
				(type default)
			)
			(layer "F.Fab")
		)
		(fp_line
			(start 0.12065 -0.2794)
			(end 0.12065 -0.3048)
			(stroke
				(width 0.1)
				(type default)
			)
			(layer "F.Fab")
		)
		(fp_line
			(start 0.67945 -0.3048)
			(end 0.67945 0.3048)
			(stroke
				(width 0.1)
				(type default)
			)
			(layer "F.Fab")
		)
		(fp_line
			(start 0.67945 0.3048)
			(end 0.120396 0.3048)
			(stroke
				(width 0.1)
				(type default)
			)
			(layer "F.Fab")
		)
		(pad "1" smd circle
			(at -0.40005 0)
			(size 0 0)
			(layers "F.Cu" "F.Mask" "F.Paste")
			(net "P3V3")
		)
		(pad "2" smd circle
			(at 0.40005 0)
			(size 0 0)
			(layers "F.Cu" "F.Mask" "F.Paste")
			(net "SMB_HOST_CLK_BUF_ISO_3V3AUX_S_2")
		)
	)
	(footprint ""
		(layer "F.Cu")
		(at 116.561616 -258.72694 90)
		(property "Reference" "C308"
			(at 0 0 90)
			(layer "F.SilkS")
			(hide yes)
			(effects
				(font
					(size 1.27 1.27)
				)
			)
		)
		(property "Value" ""
			(at 0 0 90)
			(layer "F.Fab")
			(effects
				(font
					(size 1.27 1.27)
				)
			)
		)
		(duplicate_pad_numbers_are_jumpers no)
		(fp_line
			(start 0.7874 -0.4064)
			(end 0.7874 0.4064)
			(stroke
				(width 0.1524)
				(type default)
			)
			(layer "F.SilkS")
		)
		(fp_line
			(start -0.7874 -0.4064)
			(end 0.7874 -0.4064)
			(stroke
				(width 0.1524)
				(type default)
			)
			(layer "F.SilkS")
		)
		(fp_line
			(start 0.7874 0.4064)
			(end -0.7874 0.4064)
			(stroke
				(width 0.1524)
				(type default)
			)
			(layer "F.SilkS")
		)
		(fp_line
			(start -0.7874 0.4064)
			(end -0.7874 -0.4064)
			(stroke
				(width 0.1524)
				(type default)
			)
			(layer "F.SilkS")
		)
		(fp_line
			(start -0.12065 -0.305054)
			(end -0.12065 -0.2794)
			(stroke
				(width 0.1)
				(type default)
			)
			(layer "F.Fab")
		)
		(fp_line
			(start -0.67945 -0.305054)
			(end -0.12065 -0.305054)
			(stroke
				(width 0.1)
				(type default)
			)
			(layer "F.Fab")
		)
		(fp_line
			(start 0.67945 -0.3048)
			(end 0.67945 0.3048)
			(stroke
				(width 0.1)
				(type default)
			)
			(layer "F.Fab")
		)
		(fp_line
			(start 0.12065 -0.3048)
			(end 0.67945 -0.3048)
			(stroke
				(width 0.1)
				(type default)
			)
			(layer "F.Fab")
		)
		(fp_line
			(start 0.12065 -0.2794)
			(end 0.12065 -0.3048)
			(stroke
				(width 0.1)
				(type default)
			)
			(layer "F.Fab")
		)
		(fp_line
			(start -0.12065 -0.2794)
			(end 0.12065 -0.2794)
			(stroke
				(width 0.1)
				(type default)
			)
			(layer "F.Fab")
		)
		(fp_line
			(start 0.120396 0.2794)
			(end -0.12065 0.2794)
			(stroke
				(width 0.1)
				(type default)
			)
			(layer "F.Fab")
		)
		(fp_line
			(start -0.12065 0.2794)
			(end -0.12065 0.3048)
			(stroke
				(width 0.1)
				(type default)
			)
			(layer "F.Fab")
		)
		(fp_line
			(start 0.67945 0.3048)
			(end 0.120396 0.3048)
			(stroke
				(width 0.1)
				(type default)
			)
			(layer "F.Fab")
		)
		(fp_line
			(start 0.120396 0.3048)
			(end 0.120396 0.2794)
			(stroke
				(width 0.1)
				(type default)
			)
			(layer "F.Fab")
		)
		(fp_line
			(start -0.12065 0.3048)
			(end -0.67945 0.3048)
			(stroke
				(width 0.1)
				(type default)
			)
			(layer "F.Fab")
		)
		(fp_line
			(start -0.67945 0.3048)
			(end -0.67945 -0.305054)
			(stroke
				(width 0.1)
				(type default)
			)
			(layer "F.Fab")
		)
		(pad "1" smd circle
			(at -0.40005 0 90)
			(size 0 0)
			(layers "F.Cu" "F.Mask" "F.Paste")
			(net "PVCCIN_CPU1")
		)
		(pad "2" smd circle
			(at 0.40005 0 90)
			(size 0 0)
			(layers "F.Cu" "F.Mask" "F.Paste")
			(net "GND")
		)
	)
	(footprint ""
		(layer "F.Cu")
		(at 448.787012 -62.020196 -90)
		(property "Reference" "PL66"
			(at -3.292602 -7.236968 0)
			(unlocked yes)
			(layer "F.SilkS")
			(effects
				(font
					(size 0.7874 0.5842)
					(thickness 0.1524)
				)
				(justify left)
			)
		)
		(property "Value" ""
			(at 0 0 270)
			(layer "F.Fab")
			(effects
				(font
					(size 1.27 1.27)
				)
			)
		)
		(duplicate_pad_numbers_are_jumpers no)
		(fp_line
			(start -7.1501 6.450076)
			(end -7.1501 2.6416)
			(stroke
				(width 0.1524)
				(type default)
			)
			(layer "F.SilkS")
		)
		(fp_line
			(start 7.1501 6.450076)
			(end -7.1501 6.450076)
			(stroke
				(width 0.1524)
				(type default)
			)
			(layer "F.SilkS")
		)
		(fp_line
			(start 7.1501 2.6416)
			(end 7.1501 6.450076)
			(stroke
				(width 0.1524)
				(type default)
			)
			(layer "F.SilkS")
		)
		(fp_line
			(start 7.1501 -2.6416)
			(end 7.1501 -6.450076)
			(stroke
				(width 0.1524)
				(type default)
			)
			(layer "F.SilkS")
		)
		(fp_line
			(start -7.1501 -6.450076)
			(end -7.1501 -2.6416)
			(stroke
				(width 0.1524)
				(type default)
			)
			(layer "F.SilkS")
		)
		(fp_line
			(start 7.1501 -6.450076)
			(end -7.1501 -6.450076)
			(stroke
				(width 0.1524)
				(type default)
			)
			(layer "F.SilkS")
		)
		(fp_line
			(start -7.1501 6.450076)
			(end 7.1501 6.450076)
			(stroke
				(width 0.1)
				(type default)
			)
			(layer "F.Fab")
		)
		(fp_line
			(start 7.1501 6.450076)
			(end 7.1501 -6.450076)
			(stroke
				(width 0.1)
				(type default)
			)
			(layer "F.Fab")
		)
		(fp_line
			(start -7.1501 -6.450076)
			(end -7.1501 6.450076)
			(stroke
				(width 0.1)
				(type default)
			)
			(layer "F.Fab")
		)
		(fp_line
			(start 7.1501 -6.450076)
			(end -7.1501 -6.450076)
			(stroke
				(width 0.1)
				(type default)
			)
			(layer "F.Fab")
		)
		(pad "1" smd rect
			(at -5.625084 0 270)
			(size 3.2512 5.0038)
			(layers "F.Cu" "F.Mask" "F.Paste")
			(net "SW_P3V3_AUX_SW")
		)
		(pad "2" smd rect
			(at 5.625084 0 270)
			(size 3.2512 5.0038)
			(layers "F.Cu" "F.Mask" "F.Paste")
			(net "P3V3_AUX")
		)
	)
)
